(kicad_pcb
	(version 20260206)
	(generator "pcbnew")
	(generator_version "10.0")
	(general
		(thickness 1.6)
		(legacy_teardrops no)
	)
	(paper "A4")
	(title_block
		(title "baseboard — 13948-1b.1110WZS1818.brd")
		(comment 1 "Honey Badger (Wiwynn) / footprints 310-318 of 2523")
	)
	(layers
		(0 "F.Cu" signal "TOP")
		(4 "In1.Cu" signal "L2GND")
		(6 "In2.Cu" signal "L3")
		(8 "In3.Cu" signal "L4VCC")
		(10 "In4.Cu" signal "L5VCC")
		(12 "In5.Cu" signal "L6")
		(14 "In6.Cu" signal "L7GND")
		(2 "B.Cu" signal "BOTTOM")
		(9 "F.Adhes" user "F.Adhesive")
		(11 "B.Adhes" user "B.Adhesive")
		(13 "F.Paste" user "Package Geometry/Pastemask Top")
		(15 "B.Paste" user "Package Geometry/Pastemask Bottom")
		(5 "F.SilkS" user "Ref Des/Silkscreen Top")
		(7 "B.SilkS" user "Ref Des/Silkscreen Bottom")
		(1 "F.Mask" user "Board Geometry/Soldermask Top")
		(3 "B.Mask" user "Board Geometry/Soldermask Bottom")
		(17 "Dwgs.User" user "User.Drawings")
		(19 "Cmts.User" user "User.Comments")
		(21 "Eco1.User" user "User.Eco1")
		(23 "Eco2.User" user "User.Eco2")
		(25 "Edge.Cuts" user "Board Geometry/Outline")
		(27 "Margin" user)
		(31 "F.CrtYd" user "Package Geometry/Place Bound Top")
		(29 "B.CrtYd" user "Package Geometry/Place Bound Bottom")
		(35 "F.Fab" user "Ref Des/Assembly Top")
		(33 "B.Fab" user "Ref Des/Assembly Bottom")
	)
	(footprint ""
		(layer "F.Cu")
		(at 289.56 -208.915 90)
		(property "Reference" "C177"
			(at 0 0 90)
			(layer "F.SilkS")
			(hide yes)
			(effects
				(font
					(size 1.27 1.27)
				)
			)
		)
		(property "Value" "SCD01U25V2KX-3GP"
			(at 1.1811 -2.7051 90)
			(unlocked yes)
			(layer "F.Fab")
			(hide yes)
			(effects
				(font
					(size 1.016 1.016)
					(thickness 0.1524)
				)
			)
		)
		(property "Device Type" "C402H22"
			(at 1.1811 -4.2291 90)
			(unlocked yes)
			(layer "F.Fab")
			(hide yes)
			(effects
				(font
					(size 1.016 1.016)
					(thickness 0.1524)
				)
			)
		)
		(duplicate_pad_numbers_are_jumpers no)
		(fp_rect
			(start -0.4318 0.9525)
			(end 0.4318 -0.9525)
			(stroke
				(width 0)
				(type default)
			)
			(fill no)
			(layer "F.CrtYd")
		)
		(fp_rect
			(start -0.4318 0.9525)
			(end 0.4318 -0.9525)
			(stroke
				(width 0)
				(type default)
			)
			(fill no)
			(layer "F.Fab")
		)
		(pad "1" smd custom
			(at 0 -0.4445 90)
			(size 0.1524 0.1524)
			(layers "F.Cu" "F.Mask" "F.Paste")
			(net "P1V53_STBY")
			(options
				(clearance outline)
				(anchor circle)
			)
			(primitives
				(gr_poly
					(pts
						(arc
							(start 0.3048 -0.2032)
							(mid 0.275042 -0.275042)
							(end 0.2032 -0.3048)
						)
						(arc
							(start -0.2032 -0.3048)
							(mid -0.275042 -0.275042)
							(end -0.3048 -0.2032)
						)
						(arc
							(start -0.3048 0.2032)
							(mid -0.275042 0.275042)
							(end -0.2032 0.3048)
						)
						(arc
							(start 0.2032 0.3048)
							(mid 0.275042 0.275042)
							(end 0.3048 0.2032)
						)
					)
					(width 0)
					(fill yes)
				)
			)
		)
		(pad "2" smd custom
			(at 0 0.4445 90)
			(size 0.1524 0.1524)
			(layers "F.Cu" "F.Mask" "F.Paste")
			(net "DDR_VREF")
			(options
				(clearance outline)
				(anchor circle)
			)
			(primitives
				(gr_poly
					(pts
						(arc
							(start 0.3048 -0.2032)
							(mid 0.275042 -0.275042)
							(end 0.2032 -0.3048)
						)
						(arc
							(start -0.2032 -0.3048)
							(mid -0.275042 -0.275042)
							(end -0.3048 -0.2032)
						)
						(arc
							(start -0.3048 0.2032)
							(mid -0.275042 0.275042)
							(end -0.2032 0.3048)
						)
						(arc
							(start 0.2032 0.3048)
							(mid 0.275042 0.275042)
							(end 0.3048 0.2032)
						)
					)
					(width 0)
					(fill yes)
				)
			)
		)
	)
	(footprint ""
		(layer "F.Cu")
		(at 144.907 -100.076 90)
		(property "Reference" "SC1158"
			(at 0 0 90)
			(layer "F.SilkS")
			(hide yes)
			(effects
				(font
					(size 1.27 1.27)
				)
			)
		)
		(property "Value" "SC100U6D3V0MX-2GP"
			(at -0.00254 -4.78536 90)
			(unlocked yes)
			(layer "F.Fab")
			(hide yes)
			(effects
				(font
					(size 1.016 1.016)
					(thickness 0.1524)
				)
			)
		)
		(property "Device Type" "C1210H107"
			(at -0.00254 -6.38048 90)
			(unlocked yes)
			(layer "F.Fab")
			(hide yes)
			(effects
				(font
					(size 1.016 1.016)
					(thickness 0.1524)
				)
			)
		)
		(duplicate_pad_numbers_are_jumpers no)
		(fp_line
			(start 1.5748 -2.3368)
			(end -1.5748 -2.3368)
			(stroke
				(width 0.1524)
				(type default)
			)
			(layer "F.SilkS")
		)
		(fp_line
			(start -1.5748 -2.3368)
			(end -1.5748 -0.762)
			(stroke
				(width 0.1524)
				(type default)
			)
			(layer "F.SilkS")
		)
		(fp_line
			(start 1.5748 -0.762)
			(end 1.5748 -2.3368)
			(stroke
				(width 0.1524)
				(type default)
			)
			(layer "F.SilkS")
		)
		(fp_line
			(start -1.5748 0.762)
			(end -1.5748 2.3368)
			(stroke
				(width 0.1524)
				(type default)
			)
			(layer "F.SilkS")
		)
		(fp_line
			(start 1.5748 2.3368)
			(end 1.5748 0.762)
			(stroke
				(width 0.1524)
				(type default)
			)
			(layer "F.SilkS")
		)
		(fp_line
			(start -1.5748 2.3368)
			(end 1.5748 2.3368)
			(stroke
				(width 0.1524)
				(type default)
			)
			(layer "F.SilkS")
		)
		(fp_rect
			(start -1.651 2.413)
			(end 1.651 -2.413)
			(stroke
				(width 0)
				(type default)
			)
			(fill no)
			(layer "F.CrtYd")
		)
		(fp_poly
			(pts
				(xy 1.651 2.413) (xy 1.651 -2.413) (xy -1.651 -2.413) (xy -1.651 2.413)
			)
			(stroke
				(width 0)
				(type default)
			)
			(fill no)
			(layer "F.Fab")
		)
		(pad "1" smd rect
			(at 0 -1.4732 90)
			(size 2.794 1.397)
			(layers "F.Cu" "F.Mask" "F.Paste")
			(net "GND")
		)
		(pad "2" smd rect
			(at 0 1.4732 90)
			(size 2.794 1.397)
			(layers "F.Cu" "F.Mask" "F.Paste")
			(net "GB_VDDA")
		)
	)
	(footprint ""
		(layer "F.Cu")
		(at 144.653 -109.601 -90)
		(property "Reference" "SC1171"
			(at 0 0 270)
			(layer "F.SilkS")
			(hide yes)
			(effects
				(font
					(size 1.27 1.27)
				)
			)
		)
		(property "Value" "SC22U6D3V5MX-2GP"
			(at -0.0762 -6.1214 270)
			(unlocked yes)
			(layer "F.Fab")
			(hide yes)
			(effects
				(font
					(size 1.016 1.016)
					(thickness 0.1524)
				)
			)
		)
		(property "Device Type" "C805H58"
			(at -0.0762 -8.1534 270)
			(unlocked yes)
			(layer "F.Fab")
			(hide yes)
			(effects
				(font
					(size 1.016 1.016)
					(thickness 0.1524)
				)
			)
		)
		(duplicate_pad_numbers_are_jumpers no)
		(fp_line
			(start 0.635 0)
			(end -0.635 0)
			(stroke
				(width 0.508)
				(type default)
			)
			(layer "F.SilkS")
		)
		(fp_rect
			(start -0.9652 1.778)
			(end 0.9652 -1.778)
			(stroke
				(width 0)
				(type default)
			)
			(fill no)
			(layer "F.CrtYd")
		)
		(fp_poly
			(pts
				(xy -0.9652 -1.778) (xy 0.9652 -1.778) (xy 0.9652 1.778) (xy -0.9652 1.778)
			)
			(stroke
				(width 0)
				(type default)
			)
			(fill no)
			(layer "F.Fab")
		)
		(pad "1" smd rect
			(at 0 -0.9652 270)
			(size 1.397 1.143)
			(layers "F.Cu" "F.Mask" "F.Paste")
			(net "GB_VDDA")
		)
		(pad "2" smd rect
			(at 0 0.9652 270)
			(size 1.397 1.143)
			(layers "F.Cu" "F.Mask" "F.Paste")
			(net "GND")
		)
	)
	(footprint ""
		(layer "F.Cu")
		(at 99.70897 -78.613)
		(property "Reference" "STP97"
			(at 0 0 0)
			(layer "F.SilkS")
			(hide yes)
			(effects
				(font
					(size 1.27 1.27)
				)
			)
		)
		(property "Value" "TPAD28"
			(at 0.0127 -1.8034 0)
			(unlocked yes)
			(layer "F.Fab")
			(hide yes)
			(effects
				(font
					(size 1.016 1.016)
					(thickness 0.1524)
				)
			)
		)
		(property "Device Type" "TPAD28"
			(at 0.0127 -3.3274 0)
			(unlocked yes)
			(layer "F.Fab")
			(hide yes)
			(effects
				(font
					(size 1.016 1.016)
					(thickness 0.1524)
				)
			)
		)
		(duplicate_pad_numbers_are_jumpers no)
		(fp_poly
			(pts
				(arc
					(start 0.3556 0)
					(mid -0.3556 0)
					(end 0.3556 0)
				)
			)
			(stroke
				(width 0)
				(type default)
			)
			(fill no)
			(layer "F.CrtYd")
		)
		(fp_poly
			(pts
				(arc
					(start 0.6096 0)
					(mid -0.6096 0)
					(end 0.6096 0)
				)
			)
			(stroke
				(width 0)
				(type default)
			)
			(fill no)
			(layer "F.Fab")
		)
		(pad "1" smd circle
			(at 0 0)
			(size 0.7112 0.7112)
			(layers "F.Cu" "F.Mask" "F.Paste")
			(net "EXP_IDDT")
		)
	)
	(footprint ""
		(layer "F.Cu")
		(at 119.64797 -77.597 -90)
		(property "Reference" "SC1124"
			(at 0 0 270)
			(layer "F.SilkS")
			(hide yes)
			(effects
				(font
					(size 1.27 1.27)
				)
			)
		)
		(property "Value" "SC12P50V2JN-3GP"
			(at 1.1811 -2.7051 270)
			(unlocked yes)
			(layer "F.Fab")
			(hide yes)
			(effects
				(font
					(size 1.016 1.016)
					(thickness 0.1524)
				)
			)
		)
		(property "Device Type" "C402H24"
			(at 1.1811 -4.2291 270)
			(unlocked yes)
			(layer "F.Fab")
			(hide yes)
			(effects
				(font
					(size 1.016 1.016)
					(thickness 0.1524)
				)
			)
		)
		(duplicate_pad_numbers_are_jumpers no)
		(fp_rect
			(start -0.4318 0.9525)
			(end 0.4318 -0.9525)
			(stroke
				(width 0)
				(type default)
			)
			(fill no)
			(layer "F.CrtYd")
		)
		(fp_rect
			(start -0.4318 0.9525)
			(end 0.4318 -0.9525)
			(stroke
				(width 0)
				(type default)
			)
			(fill no)
			(layer "F.Fab")
		)
		(pad "1" smd custom
			(at 0 -0.4445 270)
			(size 0.1524 0.1524)
			(layers "F.Cu" "F.Mask" "F.Paste")
			(net "EXP_REF_CLK_P")
			(options
				(clearance outline)
				(anchor circle)
			)
			(primitives
				(gr_poly
					(pts
						(arc
							(start 0.3048 -0.2032)
							(mid 0.275042 -0.275042)
							(end 0.2032 -0.3048)
						)
						(arc
							(start -0.2032 -0.3048)
							(mid -0.275042 -0.275042)
							(end -0.3048 -0.2032)
						)
						(arc
							(start -0.3048 0.2032)
							(mid -0.275042 0.275042)
							(end -0.2032 0.3048)
						)
						(arc
							(start 0.2032 0.3048)
							(mid 0.275042 0.275042)
							(end 0.3048 0.2032)
						)
					)
					(width 0)
					(fill yes)
				)
			)
		)
		(pad "2" smd custom
			(at 0 0.4445 270)
			(size 0.1524 0.1524)
			(layers "F.Cu" "F.Mask" "F.Paste")
			(net "GND")
			(options
				(clearance outline)
				(anchor circle)
			)
			(primitives
				(gr_poly
					(pts
						(arc
							(start 0.3048 -0.2032)
							(mid 0.275042 -0.275042)
							(end 0.2032 -0.3048)
						)
						(arc
							(start -0.2032 -0.3048)
							(mid -0.275042 -0.275042)
							(end -0.3048 -0.2032)
						)
						(arc
							(start -0.3048 0.2032)
							(mid -0.275042 0.275042)
							(end -0.2032 0.3048)
						)
						(arc
							(start 0.2032 0.3048)
							(mid 0.275042 0.275042)
							(end 0.3048 0.2032)
						)
					)
					(width 0)
					(fill yes)
				)
			)
		)
	)
	(footprint ""
		(layer "F.Cu")
		(at 164.560504 -24.184356 180)
		(property "Reference" "R417"
			(at 0 0 180)
			(layer "F.SilkS")
			(hide yes)
			(effects
				(font
					(size 1.27 1.27)
				)
			)
		)
		(property "Value" "0R2J-2-GP"
			(at 0.064008 -3.993896 180)
			(unlocked yes)
			(layer "F.Fab")
			(hide yes)
			(effects
				(font
					(size 1.016 1.016)
					(thickness 0.1524)
				)
			)
		)
		(property "Device Type" "R402H16"
			(at 0.064008 -5.517896 180)
			(unlocked yes)
			(layer "F.Fab")
			(hide yes)
			(effects
				(font
					(size 1.016 1.016)
					(thickness 0.1524)
				)
			)
		)
		(duplicate_pad_numbers_are_jumpers no)
		(fp_line
			(start 0.508 -0.9398)
			(end -0.508 -0.9398)
			(stroke
				(width 0.1524)
				(type default)
			)
			(layer "F.SilkS")
		)
		(fp_line
			(start -0.508 -0.9398)
			(end -0.508 0.9398)
			(stroke
				(width 0.1524)
				(type default)
			)
			(layer "F.SilkS")
		)
		(fp_rect
			(start -0.508 0.9398)
			(end 0.508 -0.9398)
			(stroke
				(width 0)
				(type default)
			)
			(fill no)
			(layer "F.CrtYd")
		)
		(fp_rect
			(start -0.508 0.9398)
			(end 0.508 -0.9398)
			(stroke
				(width 0)
				(type default)
			)
			(fill no)
			(layer "F.Fab")
		)
		(pad "1" smd custom
			(at 0 -0.4445 180)
			(size 0.1397 0.1397)
			(layers "F.Cu" "F.Mask" "F.Paste")
			(net "TP_LAN_5")
			(options
				(clearance outline)
				(anchor circle)
			)
			(primitives
				(gr_poly
					(pts
						(arc
							(start -0.1778 -0.2794)
							(mid -0.249642 -0.249642)
							(end -0.2794 -0.1778)
						)
						(arc
							(start -0.2794 0.1778)
							(mid -0.249642 0.249642)
							(end -0.1778 0.2794)
						)
						(arc
							(start 0.1778 0.2794)
							(mid 0.249642 0.249642)
							(end 0.2794 0.1778)
						)
						(arc
							(start 0.2794 -0.1778)
							(mid 0.249642 -0.249642)
							(end 0.1778 -0.2794)
						)
					)
					(width 0)
					(fill yes)
				)
			)
		)
		(pad "2" smd custom
			(at 0 0.4445 180)
			(size 0.1397 0.1397)
			(layers "F.Cu" "F.Mask" "F.Paste")
			(net "GND")
			(options
				(clearance outline)
				(anchor circle)
			)
			(primitives
				(gr_poly
					(pts
						(arc
							(start -0.1778 -0.2794)
							(mid -0.249642 -0.249642)
							(end -0.2794 -0.1778)
						)
						(arc
							(start -0.2794 0.1778)
							(mid -0.249642 0.249642)
							(end -0.1778 0.2794)
						)
						(arc
							(start 0.1778 0.2794)
							(mid 0.249642 0.249642)
							(end 0.2794 0.1778)
						)
						(arc
							(start 0.2794 -0.1778)
							(mid 0.249642 -0.249642)
							(end 0.1778 -0.2794)
						)
					)
					(width 0)
					(fill yes)
				)
			)
		)
	)
	(footprint ""
		(layer "F.Cu")
		(at 45.72 -230.886)
		(property "Reference" "C302"
			(at 0 0 0)
			(layer "F.SilkS")
			(hide yes)
			(effects
				(font
					(size 1.27 1.27)
				)
			)
		)
		(property "Value" "SC1U25V3KX-GP"
			(at 0 -2.8194 0)
			(unlocked yes)
			(layer "F.Fab")
			(hide yes)
			(effects
				(font
					(size 1.016 1.016)
					(thickness 0.1524)
				)
			)
		)
		(property "Device Type" "C603H36"
			(at 0 -4.3434 0)
			(unlocked yes)
			(layer "F.Fab")
			(hide yes)
			(effects
				(font
					(size 1.016 1.016)
					(thickness 0.1524)
				)
			)
		)
		(duplicate_pad_numbers_are_jumpers no)
		(fp_line
			(start 0.508 0)
			(end -0.508 0)
			(stroke
				(width 0.2032)
				(type default)
			)
			(layer "F.SilkS")
		)
		(fp_rect
			(start -0.5842 1.3335)
			(end 0.5842 -1.3335)
			(stroke
				(width 0)
				(type default)
			)
			(fill no)
			(layer "F.CrtYd")
		)
		(fp_rect
			(start -0.5842 1.3335)
			(end 0.5842 -1.3335)
			(stroke
				(width 0)
				(type default)
			)
			(fill no)
			(layer "F.Fab")
		)
		(pad "1" smd custom
			(at 0 -0.762)
			(size 0.2159 0.2159)
			(layers "F.Cu" "F.Mask" "F.Paste")
			(net "P12V_PCIE")
			(options
				(clearance outline)
				(anchor circle)
			)
			(primitives
				(gr_poly
					(pts
						(arc
							(start -0.3302 -0.4318)
							(mid -0.402042 -0.402042)
							(end -0.4318 -0.3302)
						)
						(arc
							(start -0.4318 0.3302)
							(mid -0.402042 0.402042)
							(end -0.3302 0.4318)
						)
						(arc
							(start 0.3302 0.4318)
							(mid 0.402042 0.402042)
							(end 0.4318 0.3302)
						)
						(arc
							(start 0.4318 -0.3302)
							(mid 0.402042 -0.402042)
							(end 0.3302 -0.4318)
						)
					)
					(width 0)
					(fill yes)
				)
			)
		)
		(pad "2" smd custom
			(at 0 0.762)
			(size 0.2159 0.2159)
			(layers "F.Cu" "F.Mask" "F.Paste")
			(net "GND")
			(options
				(clearance outline)
				(anchor circle)
			)
			(primitives
				(gr_poly
					(pts
						(arc
							(start -0.3302 -0.4318)
							(mid -0.402042 -0.402042)
							(end -0.4318 -0.3302)
						)
						(arc
							(start -0.4318 0.3302)
							(mid -0.402042 0.402042)
							(end -0.3302 0.4318)
						)
						(arc
							(start 0.3302 0.4318)
							(mid 0.402042 0.402042)
							(end 0.4318 0.3302)
						)
						(arc
							(start 0.4318 -0.3302)
							(mid 0.402042 -0.402042)
							(end 0.3302 -0.4318)
						)
					)
					(width 0)
					(fill yes)
				)
			)
		)
	)
	(footprint ""
		(layer "F.Cu")
		(at 82.92719 -57.879488 90)
		(property "Reference" "SC920"
			(at 0 0 90)
			(layer "F.SilkS")
			(hide yes)
			(effects
				(font
					(size 1.27 1.27)
				)
			)
		)
		(property "Value" "SC10U6D3V5KX-4GP"
			(at -0.0762 -6.1214 90)
			(unlocked yes)
			(layer "F.Fab")
			(hide yes)
			(effects
				(font
					(size 1.016 1.016)
					(thickness 0.1524)
				)
			)
		)
		(property "Device Type" "C805H58"
			(at -0.0762 -8.1534 90)
			(unlocked yes)
			(layer "F.Fab")
			(hide yes)
			(effects
				(font
					(size 1.016 1.016)
					(thickness 0.1524)
				)
			)
		)
		(duplicate_pad_numbers_are_jumpers no)
		(fp_line
			(start 0.635 0)
			(end -0.635 0)
			(stroke
				(width 0.508)
				(type default)
			)
			(layer "F.SilkS")
		)
		(fp_rect
			(start -0.9652 1.778)
			(end 0.9652 -1.778)
			(stroke
				(width 0)
				(type default)
			)
			(fill no)
			(layer "F.CrtYd")
		)
		(fp_poly
			(pts
				(xy -0.9652 -1.778) (xy 0.9652 -1.778) (xy 0.9652 1.778) (xy -0.9652 1.778)
			)
			(stroke
				(width 0)
				(type default)
			)
			(fill no)
			(layer "F.Fab")
		)
		(pad "1" smd rect
			(at 0 -0.9652 90)
			(size 1.397 1.143)
			(layers "F.Cu" "F.Mask" "F.Paste")
			(net "SYS_PLL_VDD")
		)
		(pad "2" smd rect
			(at 0 0.9652 90)
			(size 1.397 1.143)
			(layers "F.Cu" "F.Mask" "F.Paste")
			(net "GND")
		)
	)
	(footprint ""
		(layer "F.Cu")
		(at 116.59997 -114.3 180)
		(property "Reference" "SC1073"
			(at 0 0 180)
			(layer "F.SilkS")
			(hide yes)
			(effects
				(font
					(size 1.27 1.27)
				)
			)
		)
		(property "Value" "SCD01U10V1KX-GP"
			(at -2.8321 -1.7399 180)
			(unlocked yes)
			(layer "F.Fab")
			(hide yes)
			(effects
				(font
					(size 1.016 1.016)
					(thickness 0.1524)
				)
			)
		)
		(property "Device Type" "C0201H13"
			(at -2.8321 -3.2639 180)
			(unlocked yes)
			(layer "F.Fab")
			(hide yes)
			(effects
				(font
					(size 1.016 1.016)
					(thickness 0.1524)
				)
			)
		)
		(duplicate_pad_numbers_are_jumpers no)
		(fp_rect
			(start -0.2794 0.6477)
			(end 0.2794 -0.6477)
			(stroke
				(width 0)
				(type default)
			)
			(fill no)
			(layer "F.CrtYd")
		)
		(fp_rect
			(start -0.2794 0.6477)
			(end 0.2794 -0.6477)
			(stroke
				(width 0)
				(type default)
			)
			(fill no)
			(layer "F.Fab")
		)
		(pad "1" smd custom
			(at 0 -0.2794 180)
			(size 0.0762 0.0762)
			(layers "F.Cu" "F.Mask" "F.Paste")
			(net "SAS_HDD_TX3_P")
			(options
				(clearance outline)
				(anchor circle)
			)
			(primitives
				(gr_poly
					(pts
						(arc
							(start 0.1524 -0.127)
							(mid 0.137521 -0.162921)
							(end 0.1016 -0.1778)
						)
						(arc
							(start -0.1016 -0.1778)
							(mid -0.137521 -0.162921)
							(end -0.1524 -0.127)
						)
						(arc
							(start -0.1524 0.127)
							(mid -0.137521 0.162921)
							(end -0.1016 0.1778)
						)
						(arc
							(start 0.1016 0.1778)
							(mid 0.137521 0.162921)
							(end 0.1524 0.127)
						)
					)
					(width 0)
					(fill yes)
				)
			)
		)
		(pad "2" smd custom
			(at 0 0.2794 180)
			(size 0.0762 0.0762)
			(layers "F.Cu" "F.Mask" "F.Paste")
			(net "SAS_HDD_REDV_TX7_P")
			(options
				(clearance outline)
				(anchor circle)
			)
			(primitives
				(gr_poly
					(pts
						(arc
							(start 0.1524 -0.127)
							(mid 0.137521 -0.162921)
							(end 0.1016 -0.1778)
						)
						(arc
							(start -0.1016 -0.1778)
							(mid -0.137521 -0.162921)
							(end -0.1524 -0.127)
						)
						(arc
							(start -0.1524 0.127)
							(mid -0.137521 0.162921)
							(end -0.1016 0.1778)
						)
						(arc
							(start 0.1016 0.1778)
							(mid 0.137521 0.162921)
							(end 0.1524 0.127)
						)
					)
					(width 0)
					(fill yes)
				)
			)
		)
	)
)
